# T6G (Grand Teton) — schematic netlist excerpt (pin names and nets, part order shuffled) for the footprints in the layout excerpt that follows; sources: Cadence DE-HDL packaged netlist, KiCad conversion of 04192023_DAF0TMB3IC0_F0TG_MB_C_brd_V02_OCP.brd

R6266  Q_RES  0 5% CHIP  pkg 0402LF  page 178 : A = USB_HUB2_TI_USB_SSRXM_DN3_MRP_VDD12 ; B = P1V2_CPU0_USB2_DVDD12
C1305  Q_CAP  0.1UF 25V 10% X7R  pkg 0402  page 148 : A = P3V3_AUX ; B = GND

(kicad_pcb
	(version 20260206)
	(generator "pcbnew")
	(generator_version "10.0")
	(general
		(thickness 1.6)
		(legacy_teardrops no)
	)
	(paper "A4")
	(title_block
		(title "04192023_DAF0TMB3IC0_F0TG_MB_C_brd_V02_OCP.brd")
		(comment 1 "Grand Teton / footprints 3024-3025 of 8354")
	)
	(layers
		(0 "F.Cu" signal "TOP")
		(4 "In1.Cu" signal "GND")
		(6 "In2.Cu" signal "IN1")
		(8 "In3.Cu" signal "GND1")
		(10 "In4.Cu" signal "IN2")
		(12 "In5.Cu" signal "GND2")
		(14 "In6.Cu" signal "IN3")
		(16 "In7.Cu" signal "GND3")
		(18 "In8.Cu" signal "VCC")
		(20 "In9.Cu" signal "VCC1")
		(22 "In10.Cu" signal "GND4")
		(24 "In11.Cu" signal "IN4")
		(26 "In12.Cu" signal "GND5")
		(28 "In13.Cu" signal "IN5")
		(30 "In14.Cu" signal "GND6")
		(32 "In15.Cu" signal "IN6")
		(34 "In16.Cu" signal "GND7")
		(2 "B.Cu" signal "BOTTOM")
		(9 "F.Adhes" user "F.Adhesive")
		(11 "B.Adhes" user "B.Adhesive")
		(13 "F.Paste" user "Package Geometry/Pastemask Top")
		(15 "B.Paste" user "Package Geometry/Pastemask Bottom")
		(5 "F.SilkS" user "Ref Des/Silkscreen Top")
		(7 "B.SilkS" user "Ref Des/Silkscreen Bottom")
		(1 "F.Mask" user "Board Geometry/Soldermask Top")
		(3 "B.Mask" user "Board Geometry/Soldermask Bottom")
		(17 "Dwgs.User" user "User.Drawings")
		(19 "Cmts.User" user "User.Comments")
		(21 "Eco1.User" user "User.Eco1")
		(23 "Eco2.User" user "User.Eco2")
		(25 "Edge.Cuts" user "Board Geometry/Outline")
		(27 "Margin" user)
		(31 "F.CrtYd" user "Package Geometry/Place Bound Top")
		(29 "B.CrtYd" user "Package Geometry/Place Bound Bottom")
		(35 "F.Fab" user "Ref Des/Assembly Top")
		(33 "B.Fab" user "Ref Des/Assembly Bottom")
	)
	(footprint ""
		(layer "F.Cu")
		(at 120.68175 -28.085796)
		(property "Reference" "R6266"
			(at 0 0 0)
			(layer "F.SilkS")
			(hide yes)
			(effects
				(font
					(size 1.27 1.27)
				)
			)
		)
		(property "Value" ""
			(at 0 0 0)
			(layer "F.Fab")
			(effects
				(font
					(size 1.27 1.27)
				)
			)
		)
		(duplicate_pad_numbers_are_jumpers no)
		(fp_line
			(start -0.7874 -0.4064)
			(end 0.7874 -0.4064)
			(stroke
				(width 0.1524)
				(type default)
			)
			(layer "F.SilkS")
		)
		(fp_line
			(start -0.7874 0.4064)
			(end -0.7874 -0.4064)
			(stroke
				(width 0.1524)
				(type default)
			)
			(layer "F.SilkS")
		)
		(fp_line
			(start 0.7874 -0.4064)
			(end 0.7874 0.4064)
			(stroke
				(width 0.1524)
				(type default)
			)
			(layer "F.SilkS")
		)
		(fp_line
			(start 0.7874 0.4064)
			(end -0.7874 0.4064)
			(stroke
				(width 0.1524)
				(type default)
			)
			(layer "F.SilkS")
		)
		(fp_line
			(start -0.67945 -0.305054)
			(end -0.12065 -0.305054)
			(stroke
				(width 0.1)
				(type default)
			)
			(layer "F.Fab")
		)
		(fp_line
			(start -0.67945 0.3048)
			(end -0.67945 -0.305054)
			(stroke
				(width 0.1)
				(type default)
			)
			(layer "F.Fab")
		)
		(fp_line
			(start -0.12065 -0.305054)
			(end -0.12065 -0.2794)
			(stroke
				(width 0.1)
				(type default)
			)
			(layer "F.Fab")
		)
		(fp_line
			(start -0.12065 -0.2794)
			(end 0.12065 -0.2794)
			(stroke
				(width 0.1)
				(type default)
			)
			(layer "F.Fab")
		)
		(fp_line
			(start -0.12065 0.2794)
			(end -0.12065 0.3048)
			(stroke
				(width 0.1)
				(type default)
			)
			(layer "F.Fab")
		)
		(fp_line
			(start -0.12065 0.3048)
			(end -0.67945 0.3048)
			(stroke
				(width 0.1)
				(type default)
			)
			(layer "F.Fab")
		)
		(fp_line
			(start 0.120396 0.2794)
			(end -0.12065 0.2794)
			(stroke
				(width 0.1)
				(type default)
			)
			(layer "F.Fab")
		)
		(fp_line
			(start 0.120396 0.3048)
			(end 0.120396 0.2794)
			(stroke
				(width 0.1)
				(type default)
			)
			(layer "F.Fab")
		)
		(fp_line
			(start 0.12065 -0.3048)
			(end 0.67945 -0.3048)
			(stroke
				(width 0.1)
				(type default)
			)
			(layer "F.Fab")
		)
		(fp_line
			(start 0.12065 -0.2794)
			(end 0.12065 -0.3048)
			(stroke
				(width 0.1)
				(type default)
			)
			(layer "F.Fab")
		)
		(fp_line
			(start 0.67945 -0.3048)
			(end 0.67945 0.3048)
			(stroke
				(width 0.1)
				(type default)
			)
			(layer "F.Fab")
		)
		(fp_line
			(start 0.67945 0.3048)
			(end 0.120396 0.3048)
			(stroke
				(width 0.1)
				(type default)
			)
			(layer "F.Fab")
		)
		(pad "1" smd circle
			(at -0.40005 0)
			(size 0 0)
			(layers "F.Cu" "F.Mask" "F.Paste")
			(net "USB_HUB2_TI_USB_SSRXM_DN3_MRP_VDD12")
		)
		(pad "2" smd circle
			(at 0.40005 0)
			(size 0 0)
			(layers "F.Cu" "F.Mask" "F.Paste")
			(net "P1V2_CPU0_USB2_DVDD12")
		)
	)
	(footprint ""
		(layer "F.Cu")
		(at 156.154628 -45.64888 180)
		(property "Reference" "C1305"
			(at 0 0 180)
			(layer "F.SilkS")
			(hide yes)
			(effects
				(font
					(size 1.27 1.27)
				)
			)
		)
		(property "Value" ""
			(at 0 0 180)
			(layer "F.Fab")
			(effects
				(font
					(size 1.27 1.27)
				)
			)
		)
		(duplicate_pad_numbers_are_jumpers no)
		(fp_line
			(start 0.7874 0.4064)
			(end -0.7874 0.4064)
			(stroke
				(width 0.1524)
				(type default)
			)
			(layer "F.SilkS")
		)
		(fp_line
			(start 0.7874 -0.4064)
			(end 0.7874 0.4064)
			(stroke
				(width 0.1524)
				(type default)
			)
			(layer "F.SilkS")
		)
		(fp_line
			(start -0.7874 0.4064)
			(end -0.7874 -0.4064)
			(stroke
				(width 0.1524)
				(type default)
			)
			(layer "F.SilkS")
		)
		(fp_line
			(start -0.7874 -0.4064)
			(end 0.7874 -0.4064)
			(stroke
				(width 0.1524)
				(type default)
			)
			(layer "F.SilkS")
		)
		(fp_line
			(start 0.67945 0.3048)
			(end 0.120396 0.3048)
			(stroke
				(width 0.1)
				(type default)
			)
			(layer "F.Fab")
		)
		(fp_line
			(start 0.67945 -0.3048)
			(end 0.67945 0.3048)
			(stroke
				(width 0.1)
				(type default)
			)
			(layer "F.Fab")
		)
		(fp_line
			(start 0.12065 -0.2794)
			(end 0.12065 -0.3048)
			(stroke
				(width 0.1)
				(type default)
			)
			(layer "F.Fab")
		)
		(fp_line
			(start 0.12065 -0.3048)
			(end 0.67945 -0.3048)
			(stroke
				(width 0.1)
				(type default)
			)
			(layer "F.Fab")
		)
		(fp_line
			(start 0.120396 0.3048)
			(end 0.120396 0.2794)
			(stroke
				(width 0.1)
				(type default)
			)
			(layer "F.Fab")
		)
		(fp_line
			(start 0.120396 0.2794)
			(end -0.12065 0.2794)
			(stroke
				(width 0.1)
				(type default)
			)
			(layer "F.Fab")
		)
		(fp_line
			(start -0.12065 0.3048)
			(end -0.67945 0.3048)
			(stroke
				(width 0.1)
				(type default)
			)
			(layer "F.Fab")
		)
		(fp_line
			(start -0.12065 0.2794)
			(end -0.12065 0.3048)
			(stroke
				(width 0.1)
				(type default)
			)
			(layer "F.Fab")
		)
		(fp_line
			(start -0.12065 -0.2794)
			(end 0.12065 -0.2794)
			(stroke
				(width 0.1)
				(type default)
			)
			(layer "F.Fab")
		)
		(fp_line
			(start -0.12065 -0.305054)
			(end -0.12065 -0.2794)
			(stroke
				(width 0.1)
				(type default)
			)
			(layer "F.Fab")
		)
		(fp_line
			(start -0.67945 0.3048)
			(end -0.67945 -0.305054)
			(stroke
				(width 0.1)
				(type default)
			)
			(layer "F.Fab")
		)
		(fp_line
			(start -0.67945 -0.305054)
			(end -0.12065 -0.305054)
			(stroke
				(width 0.1)
				(type default)
			)
			(layer "F.Fab")
		)
		(pad "1" smd circle
			(at -0.40005 0 180)
			(size 0 0)
			(layers "F.Cu" "F.Mask" "F.Paste")
			(net "P3V3_AUX")
		)
		(pad "2" smd circle
			(at 0.40005 0 180)
			(size 0 0)
			(layers "F.Cu" "F.Mask" "F.Paste")
			(net "GND")
		)
	)
)
